FILE_TYPE=LIBRARY_PARTS ;
TIME=' Compilation on Fri Mar  2 10:20:31 1990  ';
PRIMITIVE 'NPN_DUAL';
 PIN
  'B'<0>:
   PIN_NUMBER='(5,2)';
   PINUSE='UNSPEC';
   NO_LOAD_CHECK='BOTH';
   NO_IO_CHECK='BOTH';
   ALLOW_CONNECT='TRUE';
  'C'<0>:
   PIN_NUMBER='(3,6)';
   PINUSE='UNSPEC';
   NO_LOAD_CHECK='BOTH';
   NO_IO_CHECK='BOTH';
   ALLOW_CONNECT='TRUE';
  'E'<0>:
   PIN_NUMBER='(4,1)';
   PINUSE='UNSPEC';
   NO_LOAD_CHECK='BOTH';
   NO_IO_CHECK='BOTH';
   ALLOW_CONNECT='TRUE';
 END_PIN;
 BODY
  PART_NAME='NPN_DUAL';
  PHYS_DES_PREFIX='Q';
 END_BODY;
END_PRIMITIVE;

PRIMITIVE 'NPN_DUAL_SOTB1E2';
 PIN
  'B'<0>:
   PIN_NUMBER='(1,4)';
   PINUSE='UNSPEC';
   NO_LOAD_CHECK='BOTH';
   NO_IO_CHECK='BOTH';
   ALLOW_CONNECT='TRUE';
  'C'<0>:
   PIN_NUMBER='(6,3)';
   PINUSE='UNSPEC';
   NO_LOAD_CHECK='BOTH';
   NO_IO_CHECK='BOTH';
   ALLOW_CONNECT='TRUE';
  'E'<0>:
   PIN_NUMBER='(2,5)';
   PINUSE='UNSPEC';
   NO_LOAD_CHECK='BOTH';
   NO_IO_CHECK='BOTH';
   ALLOW_CONNECT='TRUE';
 END_PIN;
 BODY
  PART_NAME='NPN_DUAL';
  PHYS_DES_PREFIX='Q';
 END_BODY;
END_PRIMITIVE;

END.
